FILE_TYPE = CONNECTIVITY;
{Allegro Design Entry HDL 17.4-2019 S026 (4007227) 1/17/2022}
"PAGE_NUMBER" = 441;
0"NC";
END.
